(kicad_pcb
	(version 20260206)
	(generator "pcbnew")
	(generator_version "10.0")
	(general
		(thickness 1.6)
		(legacy_teardrops no)
	)
	(paper "A4")
	(title_block
		(title "Wiwynn_Tioga_Pass_MB.brd")
		(comment 1 "Tioga Pass / footprint 190 of 4770 (U2D1), pads 3149-3261 of 3647")
	)
	(layers
		(0 "F.Cu" signal "TOP")
		(4 "In1.Cu" signal "L2GND")
		(6 "In2.Cu" signal "L3")
		(8 "In3.Cu" signal "L4GND")
		(10 "In4.Cu" signal "L5")
		(12 "In5.Cu" signal "L6GND")
		(14 "In6.Cu" signal "L7VCC")
		(16 "In7.Cu" signal "L8VCC")
		(18 "In8.Cu" signal "L9GND")
		(20 "In9.Cu" signal "L10")
		(22 "In10.Cu" signal "L11GND")
		(24 "In11.Cu" signal "L12")
		(26 "In12.Cu" signal "L13GND")
		(2 "B.Cu" signal "BOTTOM")
		(9 "F.Adhes" user "F.Adhesive")
		(11 "B.Adhes" user "B.Adhesive")
		(13 "F.Paste" user "Package Geometry/Pastemask Top")
		(15 "B.Paste" user "Package Geometry/Pastemask Bottom")
		(5 "F.SilkS" user "Ref Des/Silkscreen Top")
		(7 "B.SilkS" user "Ref Des/Silkscreen Bottom")
		(1 "F.Mask" user "Board Geometry/Soldermask Top")
		(3 "B.Mask" user "Board Geometry/Soldermask Bottom")
		(17 "Dwgs.User" user "User.Drawings")
		(19 "Cmts.User" user "User.Comments")
		(21 "Eco1.User" user "User.Eco1")
		(23 "Eco2.User" user "User.Eco2")
		(25 "Edge.Cuts" user "Board Geometry/Outline")
		(27 "Margin" user)
		(31 "F.CrtYd" user "Package Geometry/Place Bound Top")
		(29 "B.CrtYd" user "Package Geometry/Place Bound Bottom")
		(35 "F.Fab" user "Ref Des/Assembly Top")
		(33 "B.Fab" user "Ref Des/Assembly Bottom")
	)
	(footprint ""
		(layer "F.Cu")
		(at 104.99979 -76.550012 180)
		(property "Reference" "U2D1"
			(at 25.19299 30.484318 0)
			(unlocked yes)
			(layer "F.SilkS")
			(effects
				(font
					(size 0.7874 0.5842)
					(thickness 0.1524)
				)
			)
		)
		(property "Value" ""
			(at 0 0 180)
			(layer "F.Fab")
			(effects
				(font
					(size 1.27 1.27)
				)
			)
		)
		(duplicate_pad_numbers_are_jumpers no)
		(pad "J24" smd circle
			(at -17.504918 -21.140674)
			(size 0.4318 0.4318)
			(layers "F.Cu" "F.Mask" "F.Paste")
			(net "M_G_DQS_DN<16>")
		)
		(pad "J26" smd circle
			(at -15.787878 -21.140674)
			(size 0.4318 0.4318)
			(layers "F.Cu" "F.Mask" "F.Paste")
			(net "GND")
		)
		(pad "J28" smd circle
			(at -14.071092 -21.140674)
			(size 0.4318 0.4318)
			(layers "F.Cu" "F.Mask" "F.Paste")
			(net "GND")
		)
		(pad "J30" smd circle
			(at -12.354052 -21.140674)
			(size 0.4318 0.4318)
			(layers "F.Cu" "F.Mask" "F.Paste")
			(net "M_G_DQS_DN<15>")
		)
		(pad "J32" smd circle
			(at -10.637012 -21.140674)
			(size 0.4318 0.4318)
			(layers "F.Cu" "F.Mask" "F.Paste")
			(net "GND")
		)
		(pad "J34" smd circle
			(at -8.919972 -21.140674)
			(size 0.4318 0.4318)
			(layers "F.Cu" "F.Mask" "F.Paste")
			(net "GND")
		)
		(pad "J36" smd circle
			(at -7.202932 -21.140674)
			(size 0.4318 0.4318)
			(layers "F.Cu" "F.Mask" "F.Paste")
			(net "M_G_DQS_DN<14>")
		)
		(pad "J38" smd circle
			(at -5.485892 -21.140674)
			(size 0.4318 0.4318)
			(layers "F.Cu" "F.Mask" "F.Paste")
			(net "GND")
		)
		(pad "J40" smd circle
			(at -3.769106 -21.140674)
			(size 0.4318 0.4318)
			(layers "F.Cu" "F.Mask" "F.Paste")
			(net "GND")
		)
		(pad "J42" smd circle
			(at -2.052066 -21.140674)
			(size 0.4318 0.4318)
			(layers "F.Cu" "F.Mask" "F.Paste")
			(net "M_H_DQS_DN<13>")
		)
		(pad "J46" smd circle
			(at 2.910586 -22.940772)
			(size 0.4318 0.4318)
			(layers "F.Cu" "F.Mask" "F.Paste")
			(net "TP_CPU1_RSVD_269")
		)
		(pad "J48" smd circle
			(at 4.627626 -22.940772)
			(size 0.4318 0.4318)
			(layers "F.Cu" "F.Mask" "F.Paste")
			(net "M_G_MA<13>")
		)
		(pad "J50" smd circle
			(at 6.344412 -22.940772)
			(size 0.4318 0.4318)
			(layers "F.Cu" "F.Mask" "F.Paste")
			(net "M_H_CS_N<4>")
		)
		(pad "J52" smd circle
			(at 8.061452 -22.940772)
			(size 0.4318 0.4318)
			(layers "F.Cu" "F.Mask" "F.Paste")
			(net "M_H_MA<0>")
		)
		(pad "J54" smd circle
			(at 9.778492 -22.940772)
			(size 0.4318 0.4318)
			(layers "F.Cu" "F.Mask" "F.Paste")
			(net "M_G_MA<10>")
		)
		(pad "J56" smd circle
			(at 11.495532 -22.940772)
			(size 0.4318 0.4318)
			(layers "F.Cu" "F.Mask" "F.Paste")
			(net "M_G_CLK_DN<2>")
		)
		(pad "J58" smd circle
			(at 13.212572 -22.940772)
			(size 0.4318 0.4318)
			(layers "F.Cu" "F.Mask" "F.Paste")
			(net "M_H_MA<1>")
		)
		(pad "J60" smd circle
			(at 14.929612 -22.940772)
			(size 0.4318 0.4318)
			(layers "F.Cu" "F.Mask" "F.Paste")
			(net "M_G_ACT_N")
		)
		(pad "J62" smd circle
			(at 16.646398 -22.940772)
			(size 0.4318 0.4318)
			(layers "F.Cu" "F.Mask" "F.Paste")
			(net "TP_CPU1_RSVD_268")
		)
		(pad "J64" smd circle
			(at 18.363438 -22.940772)
			(size 0.4318 0.4318)
			(layers "F.Cu" "F.Mask" "F.Paste")
			(net "M_G_MA<12>")
		)
		(pad "J66" smd circle
			(at 20.080478 -22.940772)
			(size 0.4318 0.4318)
			(layers "F.Cu" "F.Mask" "F.Paste")
			(net "M_H_ECC<2>")
		)
		(pad "J68" smd circle
			(at 21.797518 -22.940772)
			(size 0.4318 0.4318)
			(layers "F.Cu" "F.Mask" "F.Paste")
			(net "M_H_DQS_DP<17>")
		)
		(pad "J70" smd circle
			(at 23.514558 -22.940772)
			(size 0.4318 0.4318)
			(layers "F.Cu" "F.Mask" "F.Paste")
			(net "M_H_ECC<0>")
		)
		(pad "J72" smd circle
			(at 25.231598 -22.940772)
			(size 0.4318 0.4318)
			(layers "F.Cu" "F.Mask" "F.Paste")
			(net "GND")
		)
		(pad "J74" smd circle
			(at 26.948384 -22.940772)
			(size 0.4318 0.4318)
			(layers "F.Cu" "F.Mask" "F.Paste")
			(net "GND")
		)
		(pad "J76" smd circle
			(at 28.665424 -22.940772)
			(size 0.4318 0.4318)
			(layers "F.Cu" "F.Mask" "F.Paste")
			(net "GND")
		)
		(pad "J78" smd circle
			(at 30.382464 -22.940772)
			(size 0.4318 0.4318)
			(layers "F.Cu" "F.Mask" "F.Paste")
			(net "M_H_DQ<23>")
		)
		(pad "J80" smd circle
			(at 32.099504 -22.940772)
			(size 0.4318 0.4318)
			(layers "F.Cu" "F.Mask" "F.Paste")
			(net "M_H_DQ<17>")
		)
		(pad "J82" smd circle
			(at 33.816544 -22.940772)
			(size 0.4318 0.4318)
			(layers "F.Cu" "F.Mask" "F.Paste")
			(net "GND")
		)
		(pad "J84" smd circle
			(at 35.533584 -22.940772)
			(size 0.4318 0.4318)
			(layers "F.Cu" "F.Mask" "F.Paste")
			(net "GND")
		)
		(pad "J86" smd custom
			(at 37.250624 -22.940772 270)
			(size 0.10795 0.10795)
			(layers "F.Cu" "F.Mask" "F.Paste")
			(net "GND")
			(options
				(clearance outline)
				(anchor circle)
			)
			(primitives
				(gr_poly
					(pts
						(arc
							(start 0.2159 -0.0381)
							(mid 0 -0.254)
							(end -0.2159 -0.0381)
						)
						(arc
							(start -0.2159 0.0381)
							(mid 0 0.254)
							(end 0.2159 0.0381)
						)
					)
					(width 0)
					(fill yes)
				)
			)
		)
		(pad "K1" smd custom
			(at -37.250624 -20.645628 90)
			(size 0.10795 0.10795)
			(layers "F.Cu" "F.Mask" "F.Paste")
			(net "GND")
			(options
				(clearance outline)
				(anchor circle)
			)
			(primitives
				(gr_poly
					(pts
						(arc
							(start 0.2159 -0.0381)
							(mid 0 -0.254)
							(end -0.2159 -0.0381)
						)
						(arc
							(start -0.2159 0.0381)
							(mid 0 0.254)
							(end 0.2159 0.0381)
						)
					)
					(width 0)
					(fill yes)
				)
			)
		)
		(pad "K3" smd circle
			(at -35.533584 -20.645628)
			(size 0.4318 0.4318)
			(layers "F.Cu" "F.Mask" "F.Paste")
			(net "UPI_CPU1_CPU0_P1P1_DN<1>")
		)
		(pad "K5" smd circle
			(at -33.816544 -20.645628)
			(size 0.4318 0.4318)
			(layers "F.Cu" "F.Mask" "F.Paste")
			(net "UPI_CPU1_CPU0_P1P1_DN<2>")
		)
		(pad "K7" smd circle
			(at -32.099504 -20.645628)
			(size 0.4318 0.4318)
			(layers "F.Cu" "F.Mask" "F.Paste")
			(net "UPI_CPU1_CPU0_P1P1_DP<5>")
		)
		(pad "K9" smd circle
			(at -30.382464 -20.645628)
			(size 0.4318 0.4318)
			(layers "F.Cu" "F.Mask" "F.Paste")
			(net "UPI_CPU1_CPU0_P1P1_DP<6>")
		)
		(pad "K11" smd circle
			(at -28.665424 -20.645628)
			(size 0.4318 0.4318)
			(layers "F.Cu" "F.Mask" "F.Paste")
			(net "GND")
		)
		(pad "K13" smd circle
			(at -26.948384 -20.645628)
			(size 0.4318 0.4318)
			(layers "F.Cu" "F.Mask" "F.Paste")
			(net "GND")
		)
		(pad "K15" smd circle
			(at -25.231598 -20.645628)
			(size 0.4318 0.4318)
			(layers "F.Cu" "F.Mask" "F.Paste")
			(net "PVCCIO_CPU1")
		)
		(pad "K17" smd circle
			(at -23.514558 -20.645628)
			(size 0.4318 0.4318)
			(layers "F.Cu" "F.Mask" "F.Paste")
			(net "GND")
		)
		(pad "K19" smd circle
			(at -21.797518 -20.645628)
			(size 0.4318 0.4318)
			(layers "F.Cu" "F.Mask" "F.Paste")
			(net "UPI_CPU1_CPU0_P1P1_DN<15>")
		)
		(pad "K21" smd circle
			(at -20.080478 -20.645628)
			(size 0.4318 0.4318)
			(layers "F.Cu" "F.Mask" "F.Paste")
			(net "UPI_CPU1_CPU0_P1P1_DN<19>")
		)
		(pad "K23" smd circle
			(at -18.363438 -20.645628)
			(size 0.4318 0.4318)
			(layers "F.Cu" "F.Mask" "F.Paste")
			(net "M_G_DQ<63>")
		)
		(pad "K25" smd circle
			(at -16.646398 -20.645628)
			(size 0.4318 0.4318)
			(layers "F.Cu" "F.Mask" "F.Paste")
			(net "M_G_DQ<56>")
		)
		(pad "K27" smd circle
			(at -14.929612 -20.645628)
			(size 0.4318 0.4318)
			(layers "F.Cu" "F.Mask" "F.Paste")
			(net "GND")
		)
		(pad "K29" smd circle
			(at -13.212572 -20.645628)
			(size 0.4318 0.4318)
			(layers "F.Cu" "F.Mask" "F.Paste")
			(net "M_G_DQ<54>")
		)
		(pad "K31" smd circle
			(at -11.495532 -20.645628)
			(size 0.4318 0.4318)
			(layers "F.Cu" "F.Mask" "F.Paste")
			(net "M_G_DQ<48>")
		)
		(pad "K33" smd circle
			(at -9.778492 -20.645628)
			(size 0.4318 0.4318)
			(layers "F.Cu" "F.Mask" "F.Paste")
			(net "GND")
		)
		(pad "K35" smd circle
			(at -8.061452 -20.645628)
			(size 0.4318 0.4318)
			(layers "F.Cu" "F.Mask" "F.Paste")
			(net "M_G_DQ<46>")
		)
		(pad "K37" smd circle
			(at -6.344412 -20.645628)
			(size 0.4318 0.4318)
			(layers "F.Cu" "F.Mask" "F.Paste")
			(net "M_G_DQ<40>")
		)
		(pad "K39" smd circle
			(at -4.627626 -20.645628)
			(size 0.4318 0.4318)
			(layers "F.Cu" "F.Mask" "F.Paste")
			(net "GND")
		)
		(pad "K41" smd circle
			(at -2.910586 -20.645628)
			(size 0.4318 0.4318)
			(layers "F.Cu" "F.Mask" "F.Paste")
			(net "M_H_DQ<38>")
		)
		(pad "K43" smd circle
			(at -1.193546 -20.645628)
			(size 0.4318 0.4318)
			(layers "F.Cu" "F.Mask" "F.Paste")
			(net "M_H_DQ<32>")
		)
		(pad "K45" smd circle
			(at 2.052066 -22.445726)
			(size 0.508 0.508)
			(layers "F.Cu" "F.Mask" "F.Paste")
			(net "M_G_CS_N<7>")
		)
		(pad "K47" smd circle
			(at 3.769106 -22.445726)
			(size 0.4318 0.4318)
			(layers "F.Cu" "F.Mask" "F.Paste")
			(net "M_G_MA<17>")
		)
		(pad "K49" smd circle
			(at 5.485892 -22.445726)
			(size 0.4318 0.4318)
			(layers "F.Cu" "F.Mask" "F.Paste")
			(net "M_G_MA<15>")
		)
		(pad "K51" smd circle
			(at 7.202932 -22.445726)
			(size 0.4318 0.4318)
			(layers "F.Cu" "F.Mask" "F.Paste")
			(net "M_H_CS_N<0>")
		)
		(pad "K53" smd circle
			(at 8.919972 -22.445726)
			(size 0.4318 0.4318)
			(layers "F.Cu" "F.Mask" "F.Paste")
			(net "M_H_PAR")
		)
		(pad "K55" smd circle
			(at 10.637012 -22.445726)
			(size 0.4318 0.4318)
			(layers "F.Cu" "F.Mask" "F.Paste")
			(net "M_H_BA<1>")
		)
		(pad "K57" smd circle
			(at 12.354052 -22.445726)
			(size 0.4318 0.4318)
			(layers "F.Cu" "F.Mask" "F.Paste")
			(net "M_H_MA<2>")
		)
		(pad "K59" smd circle
			(at 14.071092 -22.445726)
			(size 0.4318 0.4318)
			(layers "F.Cu" "F.Mask" "F.Paste")
			(net "M_H_MA<9>")
		)
		(pad "K61" smd circle
			(at 15.787878 -22.445726)
			(size 0.4318 0.4318)
			(layers "F.Cu" "F.Mask" "F.Paste")
			(net "TP_CPU1_RSVD_267")
		)
		(pad "K63" smd circle
			(at 17.504918 -22.445726)
			(size 0.4318 0.4318)
			(layers "F.Cu" "F.Mask" "F.Paste")
			(net "M_H_CKE<2>")
		)
		(pad "K65" smd circle
			(at 19.221958 -22.445726)
			(size 0.4318 0.4318)
			(layers "F.Cu" "F.Mask" "F.Paste")
			(net "GND")
		)
		(pad "K67" smd circle
			(at 20.938998 -22.445726)
			(size 0.4318 0.4318)
			(layers "F.Cu" "F.Mask" "F.Paste")
			(net "GND")
		)
		(pad "K69" smd circle
			(at 22.656038 -22.445726)
			(size 0.4318 0.4318)
			(layers "F.Cu" "F.Mask" "F.Paste")
			(net "GND")
		)
		(pad "K71" smd circle
			(at 24.373078 -22.445726)
			(size 0.4318 0.4318)
			(layers "F.Cu" "F.Mask" "F.Paste")
			(net "GND")
		)
		(pad "K73" smd circle
			(at 26.090118 -22.445726)
			(size 0.4318 0.4318)
			(layers "F.Cu" "F.Mask" "F.Paste")
			(net "GND")
		)
		(pad "K75" smd circle
			(at 27.806904 -22.445726)
			(size 0.4318 0.4318)
			(layers "F.Cu" "F.Mask" "F.Paste")
			(net "M_G_DQS_DN<12>")
		)
		(pad "K77" smd circle
			(at 29.523944 -22.445726)
			(size 0.4318 0.4318)
			(layers "F.Cu" "F.Mask" "F.Paste")
			(net "GND")
		)
		(pad "K79" smd circle
			(at 31.240984 -22.445726)
			(size 0.4318 0.4318)
			(layers "F.Cu" "F.Mask" "F.Paste")
			(net "M_H_DQS_DN<2>")
		)
		(pad "K81" smd circle
			(at 32.958024 -22.445726)
			(size 0.4318 0.4318)
			(layers "F.Cu" "F.Mask" "F.Paste")
			(net "GND")
		)
		(pad "K83" smd circle
			(at 34.675064 -22.445726)
			(size 0.4318 0.4318)
			(layers "F.Cu" "F.Mask" "F.Paste")
			(net "GND")
		)
		(pad "K85" smd circle
			(at 36.392104 -22.445726)
			(size 0.4318 0.4318)
			(layers "F.Cu" "F.Mask" "F.Paste")
			(net "GND")
		)
		(pad "L2" smd circle
			(at -36.392104 -20.150074)
			(size 0.4318 0.4318)
			(layers "F.Cu" "F.Mask" "F.Paste")
			(net "GND")
		)
		(pad "L4" smd circle
			(at -34.675064 -20.150074)
			(size 0.4318 0.4318)
			(layers "F.Cu" "F.Mask" "F.Paste")
			(net "UPI_CPU1_CPU0_P1P1_DP<1>")
		)
		(pad "L6" smd circle
			(at -32.958024 -20.150074)
			(size 0.4318 0.4318)
			(layers "F.Cu" "F.Mask" "F.Paste")
			(net "GND")
		)
		(pad "L8" smd circle
			(at -31.240984 -20.150074)
			(size 0.4318 0.4318)
			(layers "F.Cu" "F.Mask" "F.Paste")
			(net "GND")
		)
		(pad "L10" smd circle
			(at -29.523944 -20.150074)
			(size 0.4318 0.4318)
			(layers "F.Cu" "F.Mask" "F.Paste")
			(net "GND")
		)
		(pad "L12" smd circle
			(at -27.806904 -20.150074)
			(size 0.4318 0.4318)
			(layers "F.Cu" "F.Mask" "F.Paste")
			(net "UPI_CPU0_CPU1_P1P1_DN<7>")
		)
		(pad "L14" smd circle
			(at -26.090118 -20.150074)
			(size 0.4318 0.4318)
			(layers "F.Cu" "F.Mask" "F.Paste")
			(net "PVCCIO_CPU1")
		)
		(pad "L16" smd circle
			(at -24.373078 -20.150074)
			(size 0.4318 0.4318)
			(layers "F.Cu" "F.Mask" "F.Paste")
			(net "PVCCIO_CPU1")
		)
		(pad "L18" smd circle
			(at -22.656038 -20.150074)
			(size 0.4318 0.4318)
			(layers "F.Cu" "F.Mask" "F.Paste")
			(net "UPI_CPU1_CPU0_P1P1_DP<15>")
		)
		(pad "L20" smd circle
			(at -20.938998 -20.150074)
			(size 0.4318 0.4318)
			(layers "F.Cu" "F.Mask" "F.Paste")
			(net "GND")
		)
		(pad "L22" smd circle
			(at -19.221958 -20.150074)
			(size 0.4318 0.4318)
			(layers "F.Cu" "F.Mask" "F.Paste")
			(net "GND")
		)
		(pad "L24" smd circle
			(at -17.504918 -20.150074)
			(size 0.4318 0.4318)
			(layers "F.Cu" "F.Mask" "F.Paste")
			(net "M_G_DQS_DP<16>")
		)
		(pad "L26" smd circle
			(at -15.787878 -20.150074)
			(size 0.4318 0.4318)
			(layers "F.Cu" "F.Mask" "F.Paste")
			(net "M_G_DQ<60>")
		)
		(pad "L28" smd circle
			(at -14.071092 -20.150074)
			(size 0.4318 0.4318)
			(layers "F.Cu" "F.Mask" "F.Paste")
			(net "M_G_DQ<50>")
		)
		(pad "L30" smd circle
			(at -12.354052 -20.150074)
			(size 0.4318 0.4318)
			(layers "F.Cu" "F.Mask" "F.Paste")
			(net "M_G_DQS_DP<15>")
		)
		(pad "L32" smd circle
			(at -10.637012 -20.150074)
			(size 0.4318 0.4318)
			(layers "F.Cu" "F.Mask" "F.Paste")
			(net "M_G_DQ<52>")
		)
		(pad "L34" smd circle
			(at -8.919972 -20.150074)
			(size 0.4318 0.4318)
			(layers "F.Cu" "F.Mask" "F.Paste")
			(net "M_G_DQ<42>")
		)
		(pad "L36" smd circle
			(at -7.202932 -20.150074)
			(size 0.4318 0.4318)
			(layers "F.Cu" "F.Mask" "F.Paste")
			(net "M_G_DQS_DP<14>")
		)
		(pad "L38" smd circle
			(at -5.485892 -20.150074)
			(size 0.4318 0.4318)
			(layers "F.Cu" "F.Mask" "F.Paste")
			(net "M_G_DQ<44>")
		)
		(pad "L40" smd circle
			(at -3.769106 -20.150074)
			(size 0.4318 0.4318)
			(layers "F.Cu" "F.Mask" "F.Paste")
			(net "M_H_DQ<34>")
		)
		(pad "L42" smd circle
			(at -2.052066 -20.150074)
			(size 0.4318 0.4318)
			(layers "F.Cu" "F.Mask" "F.Paste")
			(net "M_H_DQS_DP<13>")
		)
		(pad "L46" smd circle
			(at 2.910586 -21.950172)
			(size 0.4318 0.4318)
			(layers "F.Cu" "F.Mask" "F.Paste")
			(net "PVDDQ_GHJ")
		)
		(pad "L48" smd circle
			(at 4.627626 -21.950172)
			(size 0.4318 0.4318)
			(layers "F.Cu" "F.Mask" "F.Paste")
			(net "PVDDQ_GHJ")
		)
		(pad "L50" smd circle
			(at 6.344412 -21.950172)
			(size 0.4318 0.4318)
			(layers "F.Cu" "F.Mask" "F.Paste")
			(net "PVDDQ_GHJ")
		)
		(pad "L52" smd circle
			(at 8.061452 -21.950172)
			(size 0.4318 0.4318)
			(layers "F.Cu" "F.Mask" "F.Paste")
			(net "PVDDQ_GHJ")
		)
		(pad "L54" smd circle
			(at 9.778492 -21.950172)
			(size 0.4318 0.4318)
			(layers "F.Cu" "F.Mask" "F.Paste")
			(net "PVDDQ_GHJ")
		)
		(pad "L56" smd circle
			(at 11.495532 -21.950172)
			(size 0.4318 0.4318)
			(layers "F.Cu" "F.Mask" "F.Paste")
			(net "PVDDQ_GHJ")
		)
		(pad "L58" smd circle
			(at 13.212572 -21.950172)
			(size 0.4318 0.4318)
			(layers "F.Cu" "F.Mask" "F.Paste")
			(net "PVDDQ_GHJ")
		)
		(pad "L60" smd circle
			(at 14.929612 -21.950172)
			(size 0.4318 0.4318)
			(layers "F.Cu" "F.Mask" "F.Paste")
			(net "PVDDQ_GHJ")
		)
		(pad "L62" smd circle
			(at 16.646398 -21.950172)
			(size 0.4318 0.4318)
			(layers "F.Cu" "F.Mask" "F.Paste")
			(net "PVDDQ_GHJ")
		)
		(pad "L64" smd circle
			(at 18.363438 -21.950172)
			(size 0.4318 0.4318)
			(layers "F.Cu" "F.Mask" "F.Paste")
			(net "M_H_CKE<3>")
		)
		(pad "L66" smd circle
			(at 20.080478 -21.950172)
			(size 0.4318 0.4318)
			(layers "F.Cu" "F.Mask" "F.Paste")
			(net "M_H_ECC<3>")
		)
		(pad "L68" smd circle
			(at 21.797518 -21.950172)
			(size 0.4318 0.4318)
			(layers "F.Cu" "F.Mask" "F.Paste")
			(net "M_H_DQS_DP<8>")
		)
		(pad "L70" smd circle
			(at 23.514558 -21.950172)
			(size 0.4318 0.4318)
			(layers "F.Cu" "F.Mask" "F.Paste")
			(net "M_H_ECC<4>")
		)
		(pad "L72" smd circle
			(at 25.231598 -21.950172)
			(size 0.4318 0.4318)
			(layers "F.Cu" "F.Mask" "F.Paste")
			(net "GND")
		)
		(pad "L74" smd circle
			(at 26.948384 -21.950172)
			(size 0.4318 0.4318)
			(layers "F.Cu" "F.Mask" "F.Paste")
			(net "M_G_DQ<30>")
		)
		(pad "L76" smd circle
			(at 28.665424 -21.950172)
			(size 0.4318 0.4318)
			(layers "F.Cu" "F.Mask" "F.Paste")
			(net "M_G_DQ<24>")
		)
		(pad "L78" smd circle
			(at 30.382464 -21.950172)
			(size 0.4318 0.4318)
			(layers "F.Cu" "F.Mask" "F.Paste")
			(net "GND")
		)
		(pad "L80" smd circle
			(at 32.099504 -21.950172)
			(size 0.4318 0.4318)
			(layers "F.Cu" "F.Mask" "F.Paste")
			(net "GND")
		)
	)
)
